# S9S_MB_2U (Grand Teton) — schematic netlist excerpt (pin names and nets, part order shuffled) for the footprints in the layout excerpt that follows; sources: Cadence DE-HDL packaged netlist, KiCad conversion of 03242023_DA0F0TMBIJ0_F0T_Motherboard_J_brd_V01_OCP.brd

C951  Q_CAP_DIFFBUS  DIFF BUS_0.22UF 6.3V 20% X6S  pkg C0201  page 173 : \1\ = P5E_CPU0_PE2_TX_C_DP<7> ; \2\ = P5E_CPU0_PE2_TX_DP<7>
R1706  Q_RES  10K 1% EMPTY  pkg 0402LF  page 260 : A = P3V3 ; B = PWRGD_P3V3_R1
R3136  Q_RES  1K 1% CHIP  pkg 0402LF  page 162 : A = P3V3_AUX ; B = OCP_V3_2_PRSNT3_R_N

(kicad_pcb
	(version 20260206)
	(generator "pcbnew")
	(generator_version "10.0")
	(general
		(thickness 1.6)
		(legacy_teardrops no)
	)
	(paper "A4")
	(title_block
		(title "03242023_DA0F0TMBIJ0_F0T_Motherboard_J_brd_V01_OCP.brd")
		(comment 1 "Grand Teton / footprints 4070-4072 of 6105")
	)
	(layers
		(0 "F.Cu" signal "TOP")
		(4 "In1.Cu" signal "GND")
		(6 "In2.Cu" signal "IN1")
		(8 "In3.Cu" signal "GND1")
		(10 "In4.Cu" signal "IN2")
		(12 "In5.Cu" signal "GND2")
		(14 "In6.Cu" signal "IN3")
		(16 "In7.Cu" signal "GND3")
		(18 "In8.Cu" signal "VCC")
		(20 "In9.Cu" signal "VCC1")
		(22 "In10.Cu" signal "GND4")
		(24 "In11.Cu" signal "IN4")
		(26 "In12.Cu" signal "GND5")
		(28 "In13.Cu" signal "IN5")
		(30 "In14.Cu" signal "GND6")
		(32 "In15.Cu" signal "IN6")
		(34 "In16.Cu" signal "GND7")
		(2 "B.Cu" signal "BOTTOM")
		(9 "F.Adhes" user "F.Adhesive")
		(11 "B.Adhes" user "B.Adhesive")
		(13 "F.Paste" user "Package Geometry/Pastemask Top")
		(15 "B.Paste" user "Package Geometry/Pastemask Bottom")
		(5 "F.SilkS" user "Ref Des/Silkscreen Top")
		(7 "B.SilkS" user "Ref Des/Silkscreen Bottom")
		(1 "F.Mask" user "Board Geometry/Soldermask Top")
		(3 "B.Mask" user "Board Geometry/Soldermask Bottom")
		(17 "Dwgs.User" user "User.Drawings")
		(19 "Cmts.User" user "User.Comments")
		(21 "Eco1.User" user "User.Eco1")
		(23 "Eco2.User" user "User.Eco2")
		(25 "Edge.Cuts" user "Board Geometry/Outline")
		(27 "Margin" user)
		(31 "F.CrtYd" user "Package Geometry/Place Bound Top")
		(29 "B.CrtYd" user "Package Geometry/Place Bound Bottom")
		(35 "F.Fab" user "Ref Des/Assembly Top")
		(33 "B.Fab" user "Ref Des/Assembly Bottom")
	)
	(footprint ""
		(layer "F.Cu")
		(at 422.13403 -49.76749 180)
		(property "Reference" "R1706"
			(at 0 0 180)
			(layer "F.SilkS")
			(hide yes)
			(effects
				(font
					(size 1.27 1.27)
				)
			)
		)
		(property "Value" ""
			(at 0 0 180)
			(layer "F.Fab")
			(effects
				(font
					(size 1.27 1.27)
				)
			)
		)
		(duplicate_pad_numbers_are_jumpers no)
		(fp_line
			(start 0.7874 0.4064)
			(end -0.7874 0.4064)
			(stroke
				(width 0.1524)
				(type default)
			)
			(layer "F.SilkS")
		)
		(fp_line
			(start 0.7874 -0.4064)
			(end 0.7874 0.4064)
			(stroke
				(width 0.1524)
				(type default)
			)
			(layer "F.SilkS")
		)
		(fp_line
			(start -0.7874 0.4064)
			(end -0.7874 -0.4064)
			(stroke
				(width 0.1524)
				(type default)
			)
			(layer "F.SilkS")
		)
		(fp_line
			(start -0.7874 -0.4064)
			(end 0.7874 -0.4064)
			(stroke
				(width 0.1524)
				(type default)
			)
			(layer "F.SilkS")
		)
		(fp_line
			(start 0.67945 0.3048)
			(end 0.120396 0.3048)
			(stroke
				(width 0.1)
				(type default)
			)
			(layer "F.Fab")
		)
		(fp_line
			(start 0.67945 -0.3048)
			(end 0.67945 0.3048)
			(stroke
				(width 0.1)
				(type default)
			)
			(layer "F.Fab")
		)
		(fp_line
			(start 0.12065 -0.2794)
			(end 0.12065 -0.3048)
			(stroke
				(width 0.1)
				(type default)
			)
			(layer "F.Fab")
		)
		(fp_line
			(start 0.12065 -0.3048)
			(end 0.67945 -0.3048)
			(stroke
				(width 0.1)
				(type default)
			)
			(layer "F.Fab")
		)
		(fp_line
			(start 0.120396 0.3048)
			(end 0.120396 0.2794)
			(stroke
				(width 0.1)
				(type default)
			)
			(layer "F.Fab")
		)
		(fp_line
			(start 0.120396 0.2794)
			(end -0.12065 0.2794)
			(stroke
				(width 0.1)
				(type default)
			)
			(layer "F.Fab")
		)
		(fp_line
			(start -0.12065 0.3048)
			(end -0.67945 0.3048)
			(stroke
				(width 0.1)
				(type default)
			)
			(layer "F.Fab")
		)
		(fp_line
			(start -0.12065 0.2794)
			(end -0.12065 0.3048)
			(stroke
				(width 0.1)
				(type default)
			)
			(layer "F.Fab")
		)
		(fp_line
			(start -0.12065 -0.2794)
			(end 0.12065 -0.2794)
			(stroke
				(width 0.1)
				(type default)
			)
			(layer "F.Fab")
		)
		(fp_line
			(start -0.12065 -0.305054)
			(end -0.12065 -0.2794)
			(stroke
				(width 0.1)
				(type default)
			)
			(layer "F.Fab")
		)
		(fp_line
			(start -0.67945 0.3048)
			(end -0.67945 -0.305054)
			(stroke
				(width 0.1)
				(type default)
			)
			(layer "F.Fab")
		)
		(fp_line
			(start -0.67945 -0.305054)
			(end -0.12065 -0.305054)
			(stroke
				(width 0.1)
				(type default)
			)
			(layer "F.Fab")
		)
		(pad "1" smd circle
			(at -0.40005 0 180)
			(size 0 0)
			(layers "F.Cu" "F.Mask" "F.Paste")
			(net "P3V3")
		)
		(pad "2" smd circle
			(at 0.40005 0 180)
			(size 0 0)
			(layers "F.Cu" "F.Mask" "F.Paste")
			(net "PWRGD_P3V3_R1")
		)
	)
	(footprint ""
		(layer "F.Cu")
		(at 20.60956 -70.814692)
		(property "Reference" "R3136"
			(at 0 0 0)
			(layer "F.SilkS")
			(hide yes)
			(effects
				(font
					(size 1.27 1.27)
				)
			)
		)
		(property "Value" ""
			(at 0 0 0)
			(layer "F.Fab")
			(effects
				(font
					(size 1.27 1.27)
				)
			)
		)
		(duplicate_pad_numbers_are_jumpers no)
		(fp_line
			(start -0.7874 -0.4064)
			(end 0.7874 -0.4064)
			(stroke
				(width 0.1524)
				(type default)
			)
			(layer "F.SilkS")
		)
		(fp_line
			(start -0.7874 0.4064)
			(end -0.7874 -0.4064)
			(stroke
				(width 0.1524)
				(type default)
			)
			(layer "F.SilkS")
		)
		(fp_line
			(start 0.7874 -0.4064)
			(end 0.7874 0.4064)
			(stroke
				(width 0.1524)
				(type default)
			)
			(layer "F.SilkS")
		)
		(fp_line
			(start 0.7874 0.4064)
			(end -0.7874 0.4064)
			(stroke
				(width 0.1524)
				(type default)
			)
			(layer "F.SilkS")
		)
		(fp_line
			(start -0.67945 -0.305054)
			(end -0.12065 -0.305054)
			(stroke
				(width 0.1)
				(type default)
			)
			(layer "F.Fab")
		)
		(fp_line
			(start -0.67945 0.3048)
			(end -0.67945 -0.305054)
			(stroke
				(width 0.1)
				(type default)
			)
			(layer "F.Fab")
		)
		(fp_line
			(start -0.12065 -0.305054)
			(end -0.12065 -0.2794)
			(stroke
				(width 0.1)
				(type default)
			)
			(layer "F.Fab")
		)
		(fp_line
			(start -0.12065 -0.2794)
			(end 0.12065 -0.2794)
			(stroke
				(width 0.1)
				(type default)
			)
			(layer "F.Fab")
		)
		(fp_line
			(start -0.12065 0.2794)
			(end -0.12065 0.3048)
			(stroke
				(width 0.1)
				(type default)
			)
			(layer "F.Fab")
		)
		(fp_line
			(start -0.12065 0.3048)
			(end -0.67945 0.3048)
			(stroke
				(width 0.1)
				(type default)
			)
			(layer "F.Fab")
		)
		(fp_line
			(start 0.120396 0.2794)
			(end -0.12065 0.2794)
			(stroke
				(width 0.1)
				(type default)
			)
			(layer "F.Fab")
		)
		(fp_line
			(start 0.120396 0.3048)
			(end 0.120396 0.2794)
			(stroke
				(width 0.1)
				(type default)
			)
			(layer "F.Fab")
		)
		(fp_line
			(start 0.12065 -0.3048)
			(end 0.67945 -0.3048)
			(stroke
				(width 0.1)
				(type default)
			)
			(layer "F.Fab")
		)
		(fp_line
			(start 0.12065 -0.2794)
			(end 0.12065 -0.3048)
			(stroke
				(width 0.1)
				(type default)
			)
			(layer "F.Fab")
		)
		(fp_line
			(start 0.67945 -0.3048)
			(end 0.67945 0.3048)
			(stroke
				(width 0.1)
				(type default)
			)
			(layer "F.Fab")
		)
		(fp_line
			(start 0.67945 0.3048)
			(end 0.120396 0.3048)
			(stroke
				(width 0.1)
				(type default)
			)
			(layer "F.Fab")
		)
		(pad "1" smd circle
			(at -0.40005 0)
			(size 0 0)
			(layers "F.Cu" "F.Mask" "F.Paste")
			(net "P3V3_AUX")
		)
		(pad "2" smd circle
			(at 0.40005 0)
			(size 0 0)
			(layers "F.Cu" "F.Mask" "F.Paste")
			(net "OCP_V3_2_PRSNT3_R_N")
		)
	)
	(footprint ""
		(layer "F.Cu")
		(at 395.90345 -402.371052 -90)
		(property "Reference" "C951"
			(at 0 0 270)
			(layer "F.SilkS")
			(hide yes)
			(effects
				(font
					(size 1.27 1.27)
				)
			)
		)
		(property "Value" ""
			(at 0 0 270)
			(layer "F.Fab")
			(effects
				(font
					(size 1.27 1.27)
				)
			)
		)
		(duplicate_pad_numbers_are_jumpers no)
		(fp_line
			(start -0.299974 0.150114)
			(end -0.299974 -0.150114)
			(stroke
				(width 0.1)
				(type default)
			)
			(layer "F.Fab")
		)
		(fp_line
			(start 0.299974 0.150114)
			(end -0.299974 0.150114)
			(stroke
				(width 0.1)
				(type default)
			)
			(layer "F.Fab")
		)
		(fp_line
			(start -0.299974 -0.150114)
			(end 0.299974 -0.150114)
			(stroke
				(width 0.1)
				(type default)
			)
			(layer "F.Fab")
		)
		(fp_line
			(start 0.299974 -0.150114)
			(end 0.299974 0.150114)
			(stroke
				(width 0.1)
				(type default)
			)
			(layer "F.Fab")
		)
		(pad "1" smd rect
			(at -0.2667 0 270)
			(size 0.3048 0.381)
			(layers "F.Cu" "F.Mask" "F.Paste")
			(net "P5E_CPU0_PE2_TX_C_DP<7>")
		)
		(pad "2" smd rect
			(at 0.2667 0 270)
			(size 0.3048 0.381)
			(layers "F.Cu" "F.Mask" "F.Paste")
			(net "P5E_CPU0_PE2_TX_DP<7>")
		)
	)
)
